(kicad_pcb
	(version 20241229)
	(generator "pcbnew")
	(generator_version "9.0")
	(general
		(thickness 1.62)
		(legacy_teardrops no)
	)
	(paper "A4")
	(title_block
		(title "OCuLink to 10GbE adapter")
		(date "2026-02-23")
		(rev "1.1.0")
		(company "Antmicro Ltd")
		(comment 1 "www.antmicro.com")
		(comment 9 "footprints 333-338 of 510")
	)
	(layers
		(0 "F.Cu" signal)
		(4 "In1.Cu" signal)
		(6 "In2.Cu" signal)
		(8 "In3.Cu" signal)
		(10 "In4.Cu" signal)
		(12 "In5.Cu" signal)
		(14 "In6.Cu" signal)
		(2 "B.Cu" signal)
		(9 "F.Adhes" user "F.Adhesive")
		(11 "B.Adhes" user "B.Adhesive")
		(13 "F.Paste" user)
		(15 "B.Paste" user)
		(5 "F.SilkS" user "F.Silkscreen")
		(7 "B.SilkS" user "B.Silkscreen")
		(1 "F.Mask" user)
		(3 "B.Mask" user)
		(17 "Dwgs.User" user "User.Drawings")
		(19 "Cmts.User" user "User.Comments")
		(21 "Eco1.User" user "User.Eco1")
		(23 "Eco2.User" user "User.Eco2")
		(25 "Edge.Cuts" user)
		(27 "Margin" user)
		(31 "F.CrtYd" user "F.Courtyard")
		(29 "B.CrtYd" user "B.Courtyard")
		(35 "F.Fab" user)
		(33 "B.Fab" user)
	)
	(footprint "antmicro-footprints:R_0402_1005Metric"
		(layer "B.Cu")
		(at 96.45 104.1 180)
		(descr "Resistor SMD 0402")
		(tags "resistor SMD 0402")
		(property "Reference" "R85"
			(at -0.9 0.283333 0)
			(layer "B.SilkS")
			(effects
				(font
					(size 0.7 0.7)
					(thickness 0.15)
				)
				(justify right top mirror)
			)
		)
		(property "Value" "R_22R_0402"
			(at -1.011843 -1.772047 0)
			(layer "B.Fab")
			(hide yes)
			(effects
				(font
					(size 0.7 0.7)
					(thickness 0.15)
				)
				(justify left bottom mirror)
			)
		)
		(property "Datasheet" "https://www.bourns.com/docs/product-datasheets/cr.pdf"
			(at 0 0 0)
			(layer "B.Fab")
			(hide yes)
			(effects
				(font
					(size 1.27 1.27)
					(thickness 0.15)
				)
				(justify mirror)
			)
		)
		(property "Description" "SMD Chip Resistor, 22 ohm, ± 1%, 62.5 mW, 0402 [1005 Metric], Thick Film, General Purpose"
			(at 0 0 0)
			(layer "B.Fab")
			(hide yes)
			(effects
				(font
					(size 1.27 1.27)
					(thickness 0.15)
				)
				(justify mirror)
			)
		)
		(property "MPN" "CR0402-FX-22R0GLF"
			(at 0 0 180)
			(unlocked yes)
			(layer "B.Fab")
			(hide yes)
			(effects
				(font
					(size 1 1)
					(thickness 0.15)
				)
				(justify mirror)
			)
		)
		(property "Manufacturer" "Bourns"
			(at 0 0 180)
			(unlocked yes)
			(layer "B.Fab")
			(hide yes)
			(effects
				(font
					(size 1 1)
					(thickness 0.15)
				)
				(justify mirror)
			)
		)
		(property "License" "Apache-2.0"
			(at 0 0 180)
			(unlocked yes)
			(layer "B.Fab")
			(hide yes)
			(effects
				(font
					(size 1 1)
					(thickness 0.15)
				)
				(justify mirror)
			)
		)
		(property "Author" "Antmicro"
			(at 0 0 180)
			(unlocked yes)
			(layer "B.Fab")
			(hide yes)
			(effects
				(font
					(size 1 1)
					(thickness 0.15)
				)
				(justify mirror)
			)
		)
		(property "Val" "22R"
			(at 0 0 180)
			(unlocked yes)
			(layer "B.Fab")
			(hide yes)
			(effects
				(font
					(size 1 1)
					(thickness 0.15)
				)
				(justify mirror)
			)
		)
		(property "Tolerance" "1%"
			(at 0 0 180)
			(unlocked yes)
			(layer "B.Fab")
			(hide yes)
			(effects
				(font
					(size 1 1)
					(thickness 0.15)
				)
				(justify mirror)
			)
		)
		(sheetname "/X710-AT2 Misc/")
		(sheetfile "x710-at2-mics.kicad_sch")
		(attr smd)
		(fp_rect
			(start -0.925 0.47)
			(end 0.925 -0.47)
			(stroke
				(width 0.05)
				(type default)
			)
			(fill no)
			(layer "B.CrtYd")
		)
		(fp_rect
			(start -0.5 0.25)
			(end 0.5 -0.25)
			(stroke
				(width 0.15)
				(type solid)
			)
			(fill no)
			(layer "B.Fab")
		)
		(pad "1" smd roundrect
			(at -0.48 0 180)
			(size 0.59 0.64)
			(layers "B.Cu" "B.Mask" "B.Paste")
			(roundrect_rratio 0.25)
			(net 362 "/X710-AT2 Misc/NCSI.RXD_0")
			(pintype "passive")
		)
		(pad "2" smd roundrect
			(at 0.48 0 180)
			(size 0.59 0.64)
			(layers "B.Cu" "B.Mask" "B.Paste")
			(roundrect_rratio 0.25)
			(net 161 "Net-(U9D-NCSI_RXD_0)")
			(pintype "passive")
		)
	)
	(footprint "antmicro-footprints:R_0402_1005Metric"
		(layer "B.Cu")
		(at 96.45 103.1)
		(descr "Resistor SMD 0402")
		(tags "resistor SMD 0402")
		(property "Reference" "R59"
			(at 0.9 -0.294444 0)
			(layer "B.SilkS")
			(effects
				(font
					(size 0.7 0.7)
					(thickness 0.15)
				)
				(justify right top mirror)
			)
		)
		(property "Value" "R_3k3_0402"
			(at -1.011843 -1.772046 0)
			(layer "B.Fab")
			(hide yes)
			(effects
				(font
					(size 0.7 0.7)
					(thickness 0.15)
				)
				(justify right top mirror)
			)
		)
		(property "Datasheet" "https://www.bourns.com/docs/product-datasheets/cr.pdf"
			(at 0 0 0)
			(layer "B.Fab")
			(hide yes)
			(effects
				(font
					(size 1.27 1.27)
					(thickness 0.15)
				)
				(justify mirror)
			)
		)
		(property "Description" "SMD Chip Resistor, 3.3 kohm, ± 1%, 63 mW, 0402 [1005 Metric], Thick Film, General Purpose"
			(at 0 0 0)
			(layer "B.Fab")
			(hide yes)
			(effects
				(font
					(size 1.27 1.27)
					(thickness 0.15)
				)
				(justify mirror)
			)
		)
		(property "MPN" "CR0402-FX-3301GLF"
			(at 0 0 0)
			(unlocked yes)
			(layer "B.Fab")
			(hide yes)
			(effects
				(font
					(size 1 1)
					(thickness 0.15)
				)
				(justify mirror)
			)
		)
		(property "Manufacturer" "Bourns"
			(at 0 0 0)
			(unlocked yes)
			(layer "B.Fab")
			(hide yes)
			(effects
				(font
					(size 1 1)
					(thickness 0.15)
				)
				(justify mirror)
			)
		)
		(property "License" "Apache-2.0"
			(at 0 0 0)
			(unlocked yes)
			(layer "B.Fab")
			(hide yes)
			(effects
				(font
					(size 1 1)
					(thickness 0.15)
				)
				(justify mirror)
			)
		)
		(property "Author" "Antmicro"
			(at 0 0 0)
			(unlocked yes)
			(layer "B.Fab")
			(hide yes)
			(effects
				(font
					(size 1 1)
					(thickness 0.15)
				)
				(justify mirror)
			)
		)
		(property "Val" "3k3"
			(at 0 0 0)
			(unlocked yes)
			(layer "B.Fab")
			(hide yes)
			(effects
				(font
					(size 1 1)
					(thickness 0.15)
				)
				(justify mirror)
			)
		)
		(property "Tolerance" "1%"
			(at 0 0 0)
			(unlocked yes)
			(layer "B.Fab")
			(hide yes)
			(effects
				(font
					(size 1 1)
					(thickness 0.15)
				)
				(justify mirror)
			)
		)
		(sheetname "/X710-AT2 10GbE/")
		(sheetfile "x710-at2-10gbe.kicad_sch")
		(attr smd)
		(fp_rect
			(start -0.925 0.47)
			(end 0.925 -0.47)
			(stroke
				(width 0.05)
				(type default)
			)
			(fill no)
			(layer "B.CrtYd")
		)
		(fp_rect
			(start -0.5 0.25)
			(end 0.5 -0.25)
			(stroke
				(width 0.15)
				(type solid)
			)
			(fill no)
			(layer "B.Fab")
		)
		(pad "1" smd roundrect
			(at -0.48 0)
			(size 0.59 0.64)
			(layers "B.Cu" "B.Mask" "B.Paste")
			(roundrect_rratio 0.25)
			(net 94 "/X710-AT2 10GbE/MDC3_SCL3")
			(pintype "passive")
		)
		(pad "2" smd roundrect
			(at 0.48 0)
			(size 0.59 0.64)
			(layers "B.Cu" "B.Mask" "B.Paste")
			(roundrect_rratio 0.25)
			(net 7 "+3V3")
			(pintype "passive")
		)
	)
	(footprint "antmicro-footprints:TP_SMD_1mm"
		(layer "B.Cu")
		(at 82.49 74.55 -90)
		(property "Reference" "TP32"
			(at -1.1 8.48 90)
			(layer "B.SilkS")
			(effects
				(font
					(size 0.7 0.7)
					(thickness 0.15)
				)
				(justify left bottom mirror)
			)
		)
		(property "Value" "TP_1mm_SMD"
			(at 0 -1.4 90)
			(layer "B.Fab")
			(hide yes)
			(effects
				(font
					(size 0.7 0.7)
					(thickness 0.15)
				)
				(justify left bottom mirror)
			)
		)
		(property "Description" "Test point 1mm SMD"
			(at 0 0 90)
			(layer "B.Fab")
			(hide yes)
			(effects
				(font
					(size 1.27 1.27)
					(thickness 0.15)
				)
				(justify mirror)
			)
		)
		(property "MPN" ""
			(at 0 0 90)
			(unlocked yes)
			(layer "B.Fab")
			(hide yes)
			(effects
				(font
					(size 1 1)
					(thickness 0.15)
				)
				(justify mirror)
			)
		)
		(property "Manufacturer" ""
			(at 0 0 90)
			(unlocked yes)
			(layer "B.Fab")
			(hide yes)
			(effects
				(font
					(size 1 1)
					(thickness 0.15)
				)
				(justify mirror)
			)
		)
		(property "Author" "Antmicro"
			(at 0 0 90)
			(unlocked yes)
			(layer "B.Fab")
			(hide yes)
			(effects
				(font
					(size 1 1)
					(thickness 0.15)
				)
				(justify mirror)
			)
		)
		(property "License" "Apache-2.0"
			(at 0 0 90)
			(unlocked yes)
			(layer "B.Fab")
			(hide yes)
			(effects
				(font
					(size 1 1)
					(thickness 0.15)
				)
				(justify mirror)
			)
		)
		(sheetname "/Power/")
		(sheetfile "power.kicad_sch")
		(attr exclude_from_pos_files exclude_from_bom)
		(fp_circle
			(center 0 0)
			(end 0.6 0)
			(stroke
				(width 0.05)
				(type default)
			)
			(fill no)
			(layer "B.CrtYd")
		)
		(pad "1" smd circle
			(at 0 0 270)
			(size 1 1)
			(layers "B.Cu" "B.Mask")
			(net 18 "+1V88")
			(pinfunction "1")
			(pintype "passive")
		)
	)
	(footprint "antmicro-footprints:TP_SMD_0.75mm"
		(layer "B.Cu")
		(at 102.05 108.7)
		(property "Reference" "TP9"
			(at -0.31 2.58 90)
			(layer "B.SilkS")
			(effects
				(font
					(size 0.7 0.7)
					(thickness 0.15)
				)
				(justify right top mirror)
			)
		)
		(property "Value" "TP_0.75mm_SMD"
			(at 0 -1.2 0)
			(layer "B.Fab")
			(hide yes)
			(effects
				(font
					(size 0.7 0.7)
					(thickness 0.15)
				)
				(justify right top mirror)
			)
		)
		(property "Description" "SMT test point"
			(at 0 0 0)
			(layer "B.Fab")
			(hide yes)
			(effects
				(font
					(size 1.27 1.27)
					(thickness 0.15)
				)
				(justify mirror)
			)
		)
		(property "MPN" ""
			(at 0 0 0)
			(unlocked yes)
			(layer "B.Fab")
			(hide yes)
			(effects
				(font
					(size 1 1)
					(thickness 0.15)
				)
				(justify mirror)
			)
		)
		(property "Manufacturer" ""
			(at 0 0 0)
			(unlocked yes)
			(layer "B.Fab")
			(hide yes)
			(effects
				(font
					(size 1 1)
					(thickness 0.15)
				)
				(justify mirror)
			)
		)
		(property "Author" "Antmicro"
			(at 0 0 0)
			(unlocked yes)
			(layer "B.Fab")
			(hide yes)
			(effects
				(font
					(size 1 1)
					(thickness 0.15)
				)
				(justify mirror)
			)
		)
		(property "License" "Apache-2.0"
			(at 0 0 0)
			(unlocked yes)
			(layer "B.Fab")
			(hide yes)
			(effects
				(font
					(size 1 1)
					(thickness 0.15)
				)
				(justify mirror)
			)
		)
		(sheetname "/X710-AT2 Misc/")
		(sheetfile "x710-at2-mics.kicad_sch")
		(attr exclude_from_pos_files exclude_from_bom)
		(fp_circle
			(center 0 0)
			(end 0.475 0)
			(stroke
				(width 0.05)
				(type default)
			)
			(fill no)
			(layer "B.CrtYd")
		)
		(pad "1" smd circle
			(at 0 0)
			(size 0.75 0.75)
			(layers "B.Cu" "B.Mask")
			(net 360 "/X710-AT2 Misc/NCSI.RXD_1")
			(pinfunction "1")
			(pintype "passive")
		)
	)
	(footprint "antmicro-footprints:C_0402_1005Metric"
		(layer "B.Cu")
		(at 92.25 102 90)
		(descr "Capacitor SMD 0402")
		(tags "capacitor SMD 0402")
		(property "Reference" "C136"
			(at 9.09 -0.447343 90)
			(layer "B.SilkS")
			(effects
				(font
					(size 0.7 0.7)
					(thickness 0.15)
				)
				(justify right top mirror)
			)
		)
		(property "Value" "C_1u_25V_0402"
			(at -1.022927 -2.155213 90)
			(layer "B.Fab")
			(hide yes)
			(effects
				(font
					(size 0.7 0.7)
					(thickness 0.15)
				)
				(justify right top mirror)
			)
		)
		(property "Datasheet" "https://www.murata.com/products/productdetail?partno=GRM155R61E105KE11%23"
			(at 0 0 90)
			(layer "B.Fab")
			(hide yes)
			(effects
				(font
					(size 1.27 1.27)
					(thickness 0.15)
				)
				(justify mirror)
			)
		)
		(property "Description" "SMD Multilayer Ceramic Capacitor, 1 µF, 25 V, 0402 [1005 Metric], ± 10%, X5R, GRM Series"
			(at 0 0 90)
			(layer "B.Fab")
			(hide yes)
			(effects
				(font
					(size 1.27 1.27)
					(thickness 0.15)
				)
				(justify mirror)
			)
		)
		(property "MPN" "GRM155R61E105KE11J"
			(at 0 0 90)
			(unlocked yes)
			(layer "B.Fab")
			(hide yes)
			(effects
				(font
					(size 1 1)
					(thickness 0.15)
				)
				(justify mirror)
			)
		)
		(property "Manufacturer" "Murata"
			(at 0 0 90)
			(unlocked yes)
			(layer "B.Fab")
			(hide yes)
			(effects
				(font
					(size 1 1)
					(thickness 0.15)
				)
				(justify mirror)
			)
		)
		(property "License" "Apache-2.0"
			(at 0 0 90)
			(unlocked yes)
			(layer "B.Fab")
			(hide yes)
			(effects
				(font
					(size 1 1)
					(thickness 0.15)
				)
				(justify mirror)
			)
		)
		(property "Author" "Antmicro"
			(at 0 0 90)
			(unlocked yes)
			(layer "B.Fab")
			(hide yes)
			(effects
				(font
					(size 1 1)
					(thickness 0.15)
				)
				(justify mirror)
			)
		)
		(property "Val" "1u"
			(at 0 0 90)
			(unlocked yes)
			(layer "B.Fab")
			(hide yes)
			(effects
				(font
					(size 1 1)
					(thickness 0.15)
				)
				(justify mirror)
			)
		)
		(property "Voltage" "25V"
			(at 0 0 90)
			(unlocked yes)
			(layer "B.Fab")
			(hide yes)
			(effects
				(font
					(size 1 1)
					(thickness 0.15)
				)
				(justify mirror)
			)
		)
		(property "Dielectric" "X5R"
			(at 0 0 90)
			(unlocked yes)
			(layer "B.Fab")
			(hide yes)
			(effects
				(font
					(size 1 1)
					(thickness 0.15)
				)
				(justify mirror)
			)
		)
		(sheetname "/X710-AT2 power/")
		(sheetfile "x710-at2-power.kicad_sch")
		(attr smd)
		(fp_rect
			(start -0.925 0.47)
			(end 0.925 -0.47)
			(stroke
				(width 0.05)
				(type default)
			)
			(fill no)
			(layer "B.CrtYd")
		)
		(fp_line
			(start 0.504 -0.248)
			(end -0.494 -0.248)
			(stroke
				(width 0.15)
				(type solid)
			)
			(layer "B.Fab")
		)
		(fp_line
			(start -0.494 -0.248)
			(end -0.494 0.25)
			(stroke
				(width 0.15)
				(type solid)
			)
			(layer "B.Fab")
		)
		(fp_line
			(start 0.504 0.25)
			(end 0.504 -0.248)
			(stroke
				(width 0.15)
				(type solid)
			)
			(layer "B.Fab")
		)
		(fp_line
			(start -0.494 0.25)
			(end 0.504 0.25)
			(stroke
				(width 0.15)
				(type solid)
			)
			(layer "B.Fab")
		)
		(pad "1" smd roundrect
			(at -0.48 0 90)
			(size 0.59 0.64)
			(layers "B.Cu" "B.Mask" "B.Paste")
			(roundrect_rratio 0.25)
			(net 28 "GND")
			(pintype "passive")
		)
		(pad "2" smd roundrect
			(at 0.48 0 90)
			(size 0.59 0.64)
			(layers "B.Cu" "B.Mask" "B.Paste")
			(roundrect_rratio 0.25)
			(net 7 "+3V3")
			(pintype "passive")
		)
	)
	(footprint "antmicro-footprints:R_0402_1005Metric"
		(layer "B.Cu")
		(at 99.16 90.164 180)
		(descr "Resistor SMD 0402")
		(tags "resistor SMD 0402")
		(property "Reference" "R120"
			(at 0.85 -0.456 0)
			(layer "B.SilkS")
			(effects
				(font
					(size 0.7 0.7)
					(thickness 0.15)
				)
				(justify left bottom mirror)
			)
		)
		(property "Value" "R_0R_0402"
			(at -1.011843 -1.772047 0)
			(layer "B.Fab")
			(hide yes)
			(effects
				(font
					(size 0.7 0.7)
					(thickness 0.15)
				)
				(justify left bottom mirror)
			)
		)
		(property "Datasheet" "https://industrial.panasonic.com/cdbs/www-data/pdf/RDA0000/AOA0000C301.pdf"
			(at 0 0 0)
			(layer "B.Fab")
			(hide yes)
			(effects
				(font
					(size 1.27 1.27)
					(thickness 0.15)
				)
				(justify mirror)
			)
		)
		(property "Description" "SMD Chip Resistor, Jumper, 0 ohm, 100 mW, 0402 [1005 Metric], Thick Film, General Purpose"
			(at 0 0 0)
			(layer "B.Fab")
			(hide yes)
			(effects
				(font
					(size 1.27 1.27)
					(thickness 0.15)
				)
				(justify mirror)
			)
		)
		(property "MPN" "ERJ2GE0R00X"
			(at 0 0 0)
			(unlocked yes)
			(layer "B.Fab")
			(hide yes)
			(effects
				(font
					(size 1 1)
					(thickness 0.15)
				)
				(justify mirror)
			)
		)
		(property "Manufacturer" "Panasonic"
			(at 0 0 0)
			(unlocked yes)
			(layer "B.Fab")
			(hide yes)
			(effects
				(font
					(size 1 1)
					(thickness 0.15)
				)
				(justify mirror)
			)
		)
		(property "License" "Apache-2.0"
			(at 0 0 0)
			(unlocked yes)
			(layer "B.Fab")
			(hide yes)
			(effects
				(font
					(size 1 1)
					(thickness 0.15)
				)
				(justify mirror)
			)
		)
		(property "Author" "Antmicro"
			(at 0 0 0)
			(unlocked yes)
			(layer "B.Fab")
			(hide yes)
			(effects
				(font
					(size 1 1)
					(thickness 0.15)
				)
				(justify mirror)
			)
		)
		(property "Val" "0R"
			(at 0 0 0)
			(unlocked yes)
			(layer "B.Fab")
			(hide yes)
			(effects
				(font
					(size 1 1)
					(thickness 0.15)
				)
				(justify mirror)
			)
		)
		(property "Tolerance" "~"
			(at 0 0 0)
			(unlocked yes)
			(layer "B.Fab")
			(hide yes)
			(effects
				(font
					(size 1 1)
					(thickness 0.15)
				)
				(justify mirror)
			)
		)
		(property "Current" "1A"
			(at 0 0 0)
			(unlocked yes)
			(layer "B.Fab")
			(hide yes)
			(effects
				(font
					(size 1 1)
					(thickness 0.15)
				)
				(justify mirror)
			)
		)
		(sheetname "/X710-AT2 PCIe/")
		(sheetfile "x710-at2-pcie.kicad_sch")
		(attr smd exclude_from_pos_files exclude_from_bom dnp)
		(fp_rect
			(start -0.925 0.47)
			(end 0.925 -0.47)
			(stroke
				(width 0.05)
				(type default)
			)
			(fill no)
			(layer "B.CrtYd")
		)
		(fp_rect
			(start -0.5 0.25)
			(end 0.5 -0.25)
			(stroke
				(width 0.15)
				(type solid)
			)
			(fill no)
			(layer "B.Fab")
		)
		(pad "1" smd roundrect
			(at -0.48 0 180)
			(size 0.59 0.64)
			(layers "B.Cu" "B.Mask" "B.Paste")
			(roundrect_rratio 0.25)
			(net 405 "/X710-AT2 PCIe/GEN_F_CLK+")
			(pintype "passive")
		)
		(pad "2" smd roundrect
			(at 0.48 0 180)
			(size 0.59 0.64)
			(layers "B.Cu" "B.Mask" "B.Paste")
			(roundrect_rratio 0.25)
			(net 402 "/X710-AT2 PCIe/CLK+")
			(pintype "passive")
		)
	)
)
